# TIMECARD (Time Appliance Project (Time Card)) — schematic netlist excerpt (pin names and nets, part order shuffled) for the footprints in the layout excerpt that follows; sources: Cadence DE-HDL packaged netlist, KiCad conversion of R4006-B0001-02_R01.brd

TP5  TP_PIONT  pkg TP010CT020B030_PTH  page 24 : \1\ = UNNAMED_524_FT4232HLREELQFP64_I
R268  RESISTOR  100KOHM 1%  pkg SMC_0402R_H016  page 22 : \1\ = XP3R3V_FPGA ; \2\ = GPS_UART_RXD

(kicad_pcb
	(version 20260206)
	(generator "pcbnew")
	(generator_version "10.0")
	(general
		(thickness 1.6)
		(legacy_teardrops no)
	)
	(paper "A4")
	(title_block
		(title "timecard-production-celestica-r4006 — R4006-B0001-02_R01.brd")
		(comment 1 "Time Appliance Project (Time Card) / footprints 429-430 of 1113")
	)
	(layers
		(0 "F.Cu" signal "TOP")
		(4 "In1.Cu" signal "L02_GND1")
		(6 "In2.Cu" signal "L03_SIG1")
		(8 "In3.Cu" signal "L04_GND2")
		(10 "In4.Cu" signal "L05_VCC1")
		(12 "In5.Cu" signal "L06_VCC2")
		(14 "In6.Cu" signal "L07_GND3")
		(16 "In7.Cu" signal "L08_SIG2")
		(18 "In8.Cu" signal "L09_GND4")
		(2 "B.Cu" signal "BOTTOM")
		(9 "F.Adhes" user "F.Adhesive")
		(11 "B.Adhes" user "B.Adhesive")
		(13 "F.Paste" user "Package Geometry/Pastemask Top")
		(15 "B.Paste" user "Package Geometry/Pastemask Bottom")
		(5 "F.SilkS" user "Ref Des/Silkscreen Top")
		(7 "B.SilkS" user "Ref Des/Silkscreen Bottom")
		(1 "F.Mask" user "Board Geometry/Soldermask Top")
		(3 "B.Mask" user "Board Geometry/Soldermask Bottom")
		(17 "Dwgs.User" user "User.Drawings")
		(19 "Cmts.User" user "User.Comments")
		(21 "Eco1.User" user "User.Eco1")
		(23 "Eco2.User" user "User.Eco2")
		(25 "Edge.Cuts" user "Board Geometry/Outline")
		(27 "Margin" user)
		(31 "F.CrtYd" user "Package Geometry/Place Bound Top")
		(29 "B.CrtYd" user "Package Geometry/Place Bound Bottom")
		(35 "F.Fab" user "Ref Des/Assembly Top")
		(33 "B.Fab" user "Ref Des/Assembly Bottom")
	)
	(footprint ""
		(layer "F.Cu")
		(at 125.349 -89.535 90)
		(property "Reference" "R268"
			(at -3.429 0.03937 90)
			(unlocked yes)
			(layer "F.SilkS")
			(effects
				(font
					(size 0.7874 0.5842)
					(thickness 0.1524)
				)
			)
		)
		(property "Value" "VAL*"
			(at 0.02032 2.13233 90)
			(unlocked yes)
			(layer "F.Fab")
			(hide yes)
			(effects
				(font
					(size 0.7874 0.5842)
					(thickness 0.1524)
				)
			)
		)
		(property "Device Type" "RESISTOR-G155-11003-01,100KOHMA"
			(at 0.008382 1.210564 90)
			(unlocked yes)
			(layer "F.Fab")
			(hide yes)
			(effects
				(font
					(size 0.7874 0.5842)
					(thickness 0.1524)
				)
			)
		)
		(property "User Part Number" "PARTNUM*"
			(at 0.02032 4.024884 90)
			(unlocked yes)
			(layer "Cmts.User")
			(hide yes)
			(effects
				(font
					(size 0.7874 0.5842)
					(thickness 0.1524)
				)
			)
		)
		(property "Tolerance" "TOL*"
			(at 0.044704 3.05435 90)
			(unlocked yes)
			(layer "Cmts.User")
			(hide yes)
			(effects
				(font
					(size 0.7874 0.5842)
					(thickness 0.1524)
				)
			)
		)
		(duplicate_pad_numbers_are_jumpers no)
		(fp_line
			(start 1.143 -0.5588)
			(end -1.143 -0.5588)
			(stroke
				(width 0.1)
				(type default)
			)
			(layer "F.SilkS")
		)
		(fp_line
			(start -1.143 -0.5588)
			(end -1.143 0.5588)
			(stroke
				(width 0.1)
				(type default)
			)
			(layer "F.SilkS")
		)
		(fp_line
			(start 1.143 0.5588)
			(end 1.143 -0.5588)
			(stroke
				(width 0.1)
				(type default)
			)
			(layer "F.SilkS")
		)
		(fp_line
			(start -1.143 0.5588)
			(end 1.143 0.5588)
			(stroke
				(width 0.1)
				(type default)
			)
			(layer "F.SilkS")
		)
		(fp_rect
			(start 1.143 -0.5588)
			(end -1.143 0.5588)
			(stroke
				(width 0)
				(type default)
			)
			(fill no)
			(layer "F.CrtYd")
		)
		(fp_line
			(start 0.508 -0.3048)
			(end -0.508 -0.3048)
			(stroke
				(width 0.1)
				(type default)
			)
			(layer "F.Fab")
		)
		(fp_line
			(start -0.508 -0.3048)
			(end -0.508 0.3048)
			(stroke
				(width 0.1)
				(type default)
			)
			(layer "F.Fab")
		)
		(fp_line
			(start 0.508 0.3048)
			(end 0.508 -0.3048)
			(stroke
				(width 0.1)
				(type default)
			)
			(layer "F.Fab")
		)
		(fp_line
			(start -0.508 0.3048)
			(end 0.508 0.3048)
			(stroke
				(width 0.1)
				(type default)
			)
			(layer "F.Fab")
		)
		(pad "1" smd rect
			(at -0.5334 0 90)
			(size 0.7112 0.6096)
			(layers "F.Cu" "F.Mask" "F.Paste")
			(net "XP3R3V_FPGA")
		)
		(pad "2" smd rect
			(at 0.5334 0 90)
			(size 0.7112 0.6096)
			(layers "F.Cu" "F.Mask" "F.Paste")
			(net "GPS_UART_RXD")
		)
		(zone
			(layer "F.Cu")
			(hatch none 0.5)
			(connect_pads
				(clearance 0)
			)
			(min_thickness 0.25)
			(keepout
				(tracks allowed)
				(vias not_allowed)
				(pads allowed)
				(copperpour not_allowed)
				(footprints allowed)
			)
			(placement
				(enabled no)
				(sheetname "")
			)
			(fill
				(thermal_gap 0.5)
				(thermal_bridge_width 0.5)
				(island_removal_mode 0)
			)
			(polygon
				(pts
					(xy 125.0442 -89.6112) (xy 125.0442 -89.4588) (xy 125.6538 -89.4588) (xy 125.6538 -89.6112)
				)
			)
		)
		(zone
			(layer "F.Cu")
			(hatch none 0.5)
			(connect_pads
				(clearance 0)
			)
			(min_thickness 0.25)
			(keepout
				(tracks not_allowed)
				(vias allowed)
				(pads allowed)
				(copperpour not_allowed)
				(footprints allowed)
			)
			(placement
				(enabled no)
				(sheetname "")
			)
			(fill
				(thermal_gap 0.5)
				(thermal_bridge_width 0.5)
				(island_removal_mode 0)
			)
			(polygon
				(pts
					(xy 125.0442 -89.6112) (xy 125.0442 -89.4588) (xy 125.6538 -89.4588) (xy 125.6538 -89.6112)
				)
			)
		)
	)
	(footprint ""
		(layer "F.Cu")
		(at 19.812 -83.947)
		(property "Reference" "TP5"
			(at 0 0 0)
			(layer "F.SilkS")
			(hide yes)
			(effects
				(font
					(size 1.27 1.27)
				)
			)
		)
		(property "Value" ""
			(at 0 0 0)
			(layer "F.Fab")
			(effects
				(font
					(size 1.27 1.27)
				)
			)
		)
		(property "Device Type" "TP_PIONT-TP010CT020B030_PTH-TPA"
			(at -1.341882 0.996696 0)
			(unlocked yes)
			(layer "F.Fab")
			(hide yes)
			(effects
				(font
					(size 0.7874 0.5842)
					(thickness 0.1524)
				)
				(justify left)
			)
		)
		(duplicate_pad_numbers_are_jumpers no)
		(fp_poly
			(pts
				(arc
					(start 0.889 0)
					(mid -0.889 0)
					(end 0.889 0)
				)
			)
			(stroke
				(width 0)
				(type default)
			)
			(fill no)
			(layer "B.CrtYd")
		)
		(fp_poly
			(pts
				(arc
					(start 0.889 0)
					(mid -0.889 0)
					(end 0.889 0)
				)
			)
			(stroke
				(width 0)
				(type default)
			)
			(fill no)
			(layer "F.CrtYd")
		)
		(pad "1" thru_hole circle
			(at 0 0)
			(size 0.508 0.508)
			(drill 0.254)
			(layers "*.Cu" "*.Mask")
			(remove_unused_layers no)
			(net "UNNAMED_524_FT4232HLREELQFP64_I")
			(clearance 0.1016)
			(padstack
				(mode front_inner_back)
				(layer "Inner"
					(shape circle)
					(size 0.508 0.508)
					(clearance 0.1016)
				)
				(layer "B.Cu"
					(shape circle)
					(size 0.762 0.762)
					(clearance -0.0254)
				)
			)
		)
	)
)
